(kicad_pcb
	(version 20260206)
	(generator "pcbnew")
	(generator_version "10.0")
	(general
		(thickness 1.6)
		(legacy_teardrops no)
	)
	(paper "A4")
	(title_block
		(title "baseboard — 13948-1b.1110WZS1818.brd")
		(comment 1 "Honey Badger (Wiwynn) / footprints 1586-1592 of 2523")
	)
	(layers
		(0 "F.Cu" signal "TOP")
		(4 "In1.Cu" signal "L2GND")
		(6 "In2.Cu" signal "L3")
		(8 "In3.Cu" signal "L4VCC")
		(10 "In4.Cu" signal "L5VCC")
		(12 "In5.Cu" signal "L6")
		(14 "In6.Cu" signal "L7GND")
		(2 "B.Cu" signal "BOTTOM")
		(9 "F.Adhes" user "F.Adhesive")
		(11 "B.Adhes" user "B.Adhesive")
		(13 "F.Paste" user "Package Geometry/Pastemask Top")
		(15 "B.Paste" user "Package Geometry/Pastemask Bottom")
		(5 "F.SilkS" user "Ref Des/Silkscreen Top")
		(7 "B.SilkS" user "Ref Des/Silkscreen Bottom")
		(1 "F.Mask" user "Board Geometry/Soldermask Top")
		(3 "B.Mask" user "Board Geometry/Soldermask Bottom")
		(17 "Dwgs.User" user "User.Drawings")
		(19 "Cmts.User" user "User.Comments")
		(21 "Eco1.User" user "User.Eco1")
		(23 "Eco2.User" user "User.Eco2")
		(25 "Edge.Cuts" user "Board Geometry/Outline")
		(27 "Margin" user)
		(31 "F.CrtYd" user "Package Geometry/Place Bound Top")
		(29 "B.CrtYd" user "Package Geometry/Place Bound Bottom")
		(35 "F.Fab" user "Ref Des/Assembly Top")
		(33 "B.Fab" user "Ref Des/Assembly Bottom")
	)
	(footprint ""
		(layer "F.Cu")
		(at 333.912718 -143.360648 90)
		(property "Reference" "R7896"
			(at 0 0 90)
			(layer "F.SilkS")
			(hide yes)
			(effects
				(font
					(size 1.27 1.27)
				)
			)
		)
		(property "Value" "4K7R2F-GP"
			(at 0.064008 -3.993896 90)
			(unlocked yes)
			(layer "F.Fab")
			(hide yes)
			(effects
				(font
					(size 1.016 1.016)
					(thickness 0.1524)
				)
			)
		)
		(property "Device Type" "R402H16"
			(at 0.064008 -5.517896 90)
			(unlocked yes)
			(layer "F.Fab")
			(hide yes)
			(effects
				(font
					(size 1.016 1.016)
					(thickness 0.1524)
				)
			)
		)
		(duplicate_pad_numbers_are_jumpers no)
		(fp_line
			(start 0.508 -0.9398)
			(end -0.508 -0.9398)
			(stroke
				(width 0.1524)
				(type default)
			)
			(layer "F.SilkS")
		)
		(fp_line
			(start -0.508 -0.9398)
			(end -0.508 0.9398)
			(stroke
				(width 0.1524)
				(type default)
			)
			(layer "F.SilkS")
		)
		(fp_rect
			(start -0.508 0.9398)
			(end 0.508 -0.9398)
			(stroke
				(width 0)
				(type default)
			)
			(fill no)
			(layer "F.CrtYd")
		)
		(fp_rect
			(start -0.508 0.9398)
			(end 0.508 -0.9398)
			(stroke
				(width 0)
				(type default)
			)
			(fill no)
			(layer "F.Fab")
		)
		(pad "1" smd custom
			(at 0 -0.4445 90)
			(size 0.1397 0.1397)
			(layers "F.Cu" "F.Mask" "F.Paste")
			(net "P3V3_STBY")
			(options
				(clearance outline)
				(anchor circle)
			)
			(primitives
				(gr_poly
					(pts
						(arc
							(start -0.1778 -0.2794)
							(mid -0.249642 -0.249642)
							(end -0.2794 -0.1778)
						)
						(arc
							(start -0.2794 0.1778)
							(mid -0.249642 0.249642)
							(end -0.1778 0.2794)
						)
						(arc
							(start 0.1778 0.2794)
							(mid 0.249642 0.249642)
							(end 0.2794 0.1778)
						)
						(arc
							(start 0.2794 -0.1778)
							(mid 0.249642 -0.249642)
							(end 0.1778 -0.2794)
						)
					)
					(width 0)
					(fill yes)
				)
			)
		)
		(pad "2" smd custom
			(at 0 0.4445 90)
			(size 0.1397 0.1397)
			(layers "F.Cu" "F.Mask" "F.Paste")
			(net "VBUS_DET")
			(options
				(clearance outline)
				(anchor circle)
			)
			(primitives
				(gr_poly
					(pts
						(arc
							(start -0.1778 -0.2794)
							(mid -0.249642 -0.249642)
							(end -0.2794 -0.1778)
						)
						(arc
							(start -0.2794 0.1778)
							(mid -0.249642 0.249642)
							(end -0.1778 0.2794)
						)
						(arc
							(start 0.1778 0.2794)
							(mid 0.249642 0.249642)
							(end 0.2794 0.1778)
						)
						(arc
							(start 0.2794 -0.1778)
							(mid 0.249642 -0.249642)
							(end 0.1778 -0.2794)
						)
					)
					(width 0)
					(fill yes)
				)
			)
		)
	)
	(footprint ""
		(layer "F.Cu")
		(at 62.357 -217.297 90)
		(property "Reference" "R2110"
			(at 0 0 90)
			(layer "F.SilkS")
			(hide yes)
			(effects
				(font
					(size 1.27 1.27)
				)
			)
		)
		(property "Value" "1KR2J-1-GP"
			(at 0.064008 -3.993896 90)
			(unlocked yes)
			(layer "F.Fab")
			(hide yes)
			(effects
				(font
					(size 1.016 1.016)
					(thickness 0.1524)
				)
			)
		)
		(property "Device Type" "R402H16"
			(at 0.064008 -5.517896 90)
			(unlocked yes)
			(layer "F.Fab")
			(hide yes)
			(effects
				(font
					(size 1.016 1.016)
					(thickness 0.1524)
				)
			)
		)
		(duplicate_pad_numbers_are_jumpers no)
		(fp_line
			(start 0.508 -0.9398)
			(end -0.508 -0.9398)
			(stroke
				(width 0.1524)
				(type default)
			)
			(layer "F.SilkS")
		)
		(fp_line
			(start -0.508 -0.9398)
			(end -0.508 0.9398)
			(stroke
				(width 0.1524)
				(type default)
			)
			(layer "F.SilkS")
		)
		(fp_rect
			(start -0.508 0.9398)
			(end 0.508 -0.9398)
			(stroke
				(width 0)
				(type default)
			)
			(fill no)
			(layer "F.CrtYd")
		)
		(fp_rect
			(start -0.508 0.9398)
			(end 0.508 -0.9398)
			(stroke
				(width 0)
				(type default)
			)
			(fill no)
			(layer "F.Fab")
		)
		(pad "1" smd custom
			(at 0 -0.4445 90)
			(size 0.1397 0.1397)
			(layers "F.Cu" "F.Mask" "F.Paste")
			(net "MB0_CM_VOUT_R")
			(options
				(clearance outline)
				(anchor circle)
			)
			(primitives
				(gr_poly
					(pts
						(arc
							(start -0.1778 -0.2794)
							(mid -0.249642 -0.249642)
							(end -0.2794 -0.1778)
						)
						(arc
							(start -0.2794 0.1778)
							(mid -0.249642 0.249642)
							(end -0.1778 0.2794)
						)
						(arc
							(start 0.1778 0.2794)
							(mid 0.249642 0.249642)
							(end 0.2794 0.1778)
						)
						(arc
							(start 0.2794 -0.1778)
							(mid 0.249642 -0.249642)
							(end 0.1778 -0.2794)
						)
					)
					(width 0)
					(fill yes)
				)
			)
		)
		(pad "2" smd custom
			(at 0 0.4445 90)
			(size 0.1397 0.1397)
			(layers "F.Cu" "F.Mask" "F.Paste")
			(net "P12V")
			(options
				(clearance outline)
				(anchor circle)
			)
			(primitives
				(gr_poly
					(pts
						(arc
							(start -0.1778 -0.2794)
							(mid -0.249642 -0.249642)
							(end -0.2794 -0.1778)
						)
						(arc
							(start -0.2794 0.1778)
							(mid -0.249642 0.249642)
							(end -0.1778 0.2794)
						)
						(arc
							(start 0.1778 0.2794)
							(mid 0.249642 0.249642)
							(end 0.2794 0.1778)
						)
						(arc
							(start 0.2794 -0.1778)
							(mid 0.249642 -0.249642)
							(end 0.1778 -0.2794)
						)
					)
					(width 0)
					(fill yes)
				)
			)
		)
	)
	(footprint ""
		(layer "F.Cu")
		(at 334.645 -229.743 180)
		(property "Reference" "R187"
			(at 0 0 180)
			(layer "F.SilkS")
			(hide yes)
			(effects
				(font
					(size 1.27 1.27)
				)
			)
		)
		(property "Value" "4K7R2F-GP"
			(at 0.064008 -3.993896 180)
			(unlocked yes)
			(layer "F.Fab")
			(hide yes)
			(effects
				(font
					(size 1.016 1.016)
					(thickness 0.1524)
				)
			)
		)
		(property "Device Type" "R402H16"
			(at 0.064008 -5.517896 180)
			(unlocked yes)
			(layer "F.Fab")
			(hide yes)
			(effects
				(font
					(size 1.016 1.016)
					(thickness 0.1524)
				)
			)
		)
		(duplicate_pad_numbers_are_jumpers no)
		(fp_line
			(start 0.508 -0.9398)
			(end -0.508 -0.9398)
			(stroke
				(width 0.1524)
				(type default)
			)
			(layer "F.SilkS")
		)
		(fp_line
			(start -0.508 -0.9398)
			(end -0.508 0.9398)
			(stroke
				(width 0.1524)
				(type default)
			)
			(layer "F.SilkS")
		)
		(fp_rect
			(start -0.508 0.9398)
			(end 0.508 -0.9398)
			(stroke
				(width 0)
				(type default)
			)
			(fill no)
			(layer "F.CrtYd")
		)
		(fp_rect
			(start -0.508 0.9398)
			(end 0.508 -0.9398)
			(stroke
				(width 0)
				(type default)
			)
			(fill no)
			(layer "F.Fab")
		)
		(pad "1" smd custom
			(at 0 -0.4445 180)
			(size 0.1397 0.1397)
			(layers "F.Cu" "F.Mask" "F.Paste")
			(net "VOL_SEN_ADDR")
			(options
				(clearance outline)
				(anchor circle)
			)
			(primitives
				(gr_poly
					(pts
						(arc
							(start -0.1778 -0.2794)
							(mid -0.249642 -0.249642)
							(end -0.2794 -0.1778)
						)
						(arc
							(start -0.2794 0.1778)
							(mid -0.249642 0.249642)
							(end -0.1778 0.2794)
						)
						(arc
							(start 0.1778 0.2794)
							(mid 0.249642 0.249642)
							(end 0.2794 0.1778)
						)
						(arc
							(start 0.2794 -0.1778)
							(mid 0.249642 -0.249642)
							(end 0.1778 -0.2794)
						)
					)
					(width 0)
					(fill yes)
				)
			)
		)
		(pad "2" smd custom
			(at 0 0.4445 180)
			(size 0.1397 0.1397)
			(layers "F.Cu" "F.Mask" "F.Paste")
			(net "GND")
			(options
				(clearance outline)
				(anchor circle)
			)
			(primitives
				(gr_poly
					(pts
						(arc
							(start -0.1778 -0.2794)
							(mid -0.249642 -0.249642)
							(end -0.2794 -0.1778)
						)
						(arc
							(start -0.2794 0.1778)
							(mid -0.249642 0.249642)
							(end -0.1778 0.2794)
						)
						(arc
							(start 0.1778 0.2794)
							(mid 0.249642 0.249642)
							(end 0.2794 0.1778)
						)
						(arc
							(start 0.2794 -0.1778)
							(mid 0.249642 -0.249642)
							(end 0.1778 -0.2794)
						)
					)
					(width 0)
					(fill yes)
				)
			)
		)
	)
	(footprint ""
		(layer "F.Cu")
		(at 319.278 -9.652)
		(property "Reference" "R531"
			(at 0 0 0)
			(layer "F.SilkS")
			(hide yes)
			(effects
				(font
					(size 1.27 1.27)
				)
			)
		)
		(property "Value" "220R2F-GP"
			(at 0.064008 -3.993896 0)
			(unlocked yes)
			(layer "F.Fab")
			(hide yes)
			(effects
				(font
					(size 1.016 1.016)
					(thickness 0.1524)
				)
			)
		)
		(property "Device Type" "R402H16"
			(at 0.064008 -5.517896 0)
			(unlocked yes)
			(layer "F.Fab")
			(hide yes)
			(effects
				(font
					(size 1.016 1.016)
					(thickness 0.1524)
				)
			)
		)
		(duplicate_pad_numbers_are_jumpers no)
		(fp_line
			(start -0.508 -0.9398)
			(end -0.508 0.9398)
			(stroke
				(width 0.1524)
				(type default)
			)
			(layer "F.SilkS")
		)
		(fp_line
			(start 0.508 -0.9398)
			(end -0.508 -0.9398)
			(stroke
				(width 0.1524)
				(type default)
			)
			(layer "F.SilkS")
		)
		(fp_rect
			(start -0.508 0.9398)
			(end 0.508 -0.9398)
			(stroke
				(width 0)
				(type default)
			)
			(fill no)
			(layer "F.CrtYd")
		)
		(fp_rect
			(start -0.508 0.9398)
			(end 0.508 -0.9398)
			(stroke
				(width 0)
				(type default)
			)
			(fill no)
			(layer "F.Fab")
		)
		(pad "1" smd custom
			(at 0 -0.4445)
			(size 0.1397 0.1397)
			(layers "F.Cu" "F.Mask" "F.Paste")
			(net "LED_SL_SW_ON")
			(options
				(clearance outline)
				(anchor circle)
			)
			(primitives
				(gr_poly
					(pts
						(arc
							(start -0.1778 -0.2794)
							(mid -0.249642 -0.249642)
							(end -0.2794 -0.1778)
						)
						(arc
							(start -0.2794 0.1778)
							(mid -0.249642 0.249642)
							(end -0.1778 0.2794)
						)
						(arc
							(start 0.1778 0.2794)
							(mid 0.249642 0.249642)
							(end 0.2794 0.1778)
						)
						(arc
							(start 0.2794 -0.1778)
							(mid 0.249642 -0.249642)
							(end 0.1778 -0.2794)
						)
					)
					(width 0)
					(fill yes)
				)
			)
		)
		(pad "2" smd custom
			(at 0 0.4445)
			(size 0.1397 0.1397)
			(layers "F.Cu" "F.Mask" "F.Paste")
			(net "P3V3_STBY")
			(options
				(clearance outline)
				(anchor circle)
			)
			(primitives
				(gr_poly
					(pts
						(arc
							(start -0.1778 -0.2794)
							(mid -0.249642 -0.249642)
							(end -0.2794 -0.1778)
						)
						(arc
							(start -0.2794 0.1778)
							(mid -0.249642 0.249642)
							(end -0.1778 0.2794)
						)
						(arc
							(start 0.1778 0.2794)
							(mid 0.249642 0.249642)
							(end 0.2794 0.1778)
						)
						(arc
							(start 0.2794 -0.1778)
							(mid 0.249642 -0.249642)
							(end 0.1778 -0.2794)
						)
					)
					(width 0)
					(fill yes)
				)
			)
		)
	)
	(footprint ""
		(layer "F.Cu")
		(at 54.4576 -230.0986 180)
		(property "Reference" "D37"
			(at 0 0 180)
			(layer "F.SilkS")
			(hide yes)
			(effects
				(font
					(size 1.27 1.27)
				)
			)
		)
		(property "Value" "SMF15A-GP"
			(at -2.0955 1.2192 180)
			(unlocked yes)
			(layer "F.Fab")
			(hide yes)
			(effects
				(font
					(size 1.016 1.016)
					(thickness 0.1524)
				)
			)
		)
		(property "Device Type" "SOD123AK-2H43"
			(at -2.0955 -0.3048 180)
			(unlocked yes)
			(layer "F.Fab")
			(hide yes)
			(effects
				(font
					(size 1.016 1.016)
					(thickness 0.1524)
				)
			)
		)
		(duplicate_pad_numbers_are_jumpers no)
		(fp_line
			(start 1.1557 2.921)
			(end -1.1557 2.921)
			(stroke
				(width 0.508)
				(type default)
			)
			(layer "F.SilkS")
		)
		(fp_line
			(start 1.1557 2.7686)
			(end 1.1557 -2.7686)
			(stroke
				(width 0.1524)
				(type default)
			)
			(layer "F.SilkS")
		)
		(fp_line
			(start 1.1557 -2.7686)
			(end -1.1557 -2.7686)
			(stroke
				(width 0.1524)
				(type default)
			)
			(layer "F.SilkS")
		)
		(fp_line
			(start -1.1557 2.7686)
			(end 1.1557 2.7686)
			(stroke
				(width 0.1524)
				(type default)
			)
			(layer "F.SilkS")
		)
		(fp_line
			(start -1.1557 -2.7686)
			(end -1.1557 2.7686)
			(stroke
				(width 0.1524)
				(type default)
			)
			(layer "F.SilkS")
		)
		(fp_poly
			(pts
				(xy -0.4572 1.8669) (xy -0.4572 1.397) (xy -0.9017 1.397) (xy -0.9017 -1.397) (xy -0.4572 -1.397)
				(xy -0.4572 -1.8669) (xy 0.4572 -1.8669) (xy 0.4572 -1.397) (xy 0.9017 -1.397) (xy 0.9017 1.397)
				(xy 0.4572 1.397) (xy 0.4572 1.8669)
			)
			(stroke
				(width 0)
				(type default)
			)
			(fill no)
			(layer "F.CrtYd")
		)
		(fp_poly
			(pts
				(xy -1.4097 2.8448) (xy -1.4097 -2.8448) (xy 1.4097 -2.8448) (xy 1.4097 1.3716) (xy 0.9017 1.3716)
				(xy 0.9017 -1.397) (xy 0.4572 -1.397) (xy 0.4572 -1.8669) (xy -0.4572 -1.8669) (xy -0.4572 -1.397)
				(xy -0.9017 -1.397) (xy -0.9017 1.397) (xy -0.4572 1.397) (xy -0.4572 1.8669) (xy 0.4572 1.8669)
				(xy 0.4572 1.397) (xy 0.9017 1.397) (xy 0.9017 1.3843) (xy 1.4097 1.3843) (xy 1.4097 2.8448)
			)
			(stroke
				(width 0)
				(type default)
			)
			(fill no)
			(layer "F.CrtYd")
		)
		(fp_rect
			(start -1.4097 2.8448)
			(end 1.4097 -2.8448)
			(stroke
				(width 0)
				(type default)
			)
			(fill no)
			(layer "F.Fab")
		)
		(pad "A" smd rect
			(at 0 -1.75768 180)
			(size 1.143 1.4986)
			(layers "F.Cu" "F.Mask" "F.Paste")
			(net "GND")
		)
		(pad "K" smd rect
			(at 0 1.75768 180)
			(size 1.143 1.4986)
			(layers "F.Cu" "F.Mask" "F.Paste")
			(net "P12V_PCIE")
		)
	)
	(footprint ""
		(layer "F.Cu")
		(at 6.300216 -215.82888 -90)
		(property "Reference" "R622"
			(at 0 0 270)
			(layer "F.SilkS")
			(hide yes)
			(effects
				(font
					(size 1.27 1.27)
				)
			)
		)
		(property "Value" "10KR2F-2-GP"
			(at 0.064008 -3.993896 270)
			(unlocked yes)
			(layer "F.Fab")
			(hide yes)
			(effects
				(font
					(size 1.016 1.016)
					(thickness 0.1524)
				)
			)
		)
		(property "Device Type" "R402H16"
			(at 0.064008 -5.517896 270)
			(unlocked yes)
			(layer "F.Fab")
			(hide yes)
			(effects
				(font
					(size 1.016 1.016)
					(thickness 0.1524)
				)
			)
		)
		(duplicate_pad_numbers_are_jumpers no)
		(fp_line
			(start -0.508 -0.9398)
			(end -0.508 0.9398)
			(stroke
				(width 0.1524)
				(type default)
			)
			(layer "F.SilkS")
		)
		(fp_line
			(start 0.508 -0.9398)
			(end -0.508 -0.9398)
			(stroke
				(width 0.1524)
				(type default)
			)
			(layer "F.SilkS")
		)
		(fp_rect
			(start -0.508 0.9398)
			(end 0.508 -0.9398)
			(stroke
				(width 0)
				(type default)
			)
			(fill no)
			(layer "F.CrtYd")
		)
		(fp_rect
			(start -0.508 0.9398)
			(end 0.508 -0.9398)
			(stroke
				(width 0)
				(type default)
			)
			(fill no)
			(layer "F.Fab")
		)
		(pad "1" smd custom
			(at 0 -0.4445 270)
			(size 0.1397 0.1397)
			(layers "F.Cu" "F.Mask" "F.Paste")
			(net "PRSNT_AND_3")
			(options
				(clearance outline)
				(anchor circle)
			)
			(primitives
				(gr_poly
					(pts
						(arc
							(start -0.1778 -0.2794)
							(mid -0.249642 -0.249642)
							(end -0.2794 -0.1778)
						)
						(arc
							(start -0.2794 0.1778)
							(mid -0.249642 0.249642)
							(end -0.1778 0.2794)
						)
						(arc
							(start 0.1778 0.2794)
							(mid 0.249642 0.249642)
							(end 0.2794 0.1778)
						)
						(arc
							(start 0.2794 -0.1778)
							(mid 0.249642 -0.249642)
							(end 0.1778 -0.2794)
						)
					)
					(width 0)
					(fill yes)
				)
			)
		)
		(pad "2" smd custom
			(at 0 0.4445 270)
			(size 0.1397 0.1397)
			(layers "F.Cu" "F.Mask" "F.Paste")
			(net "P3V3_STBY")
			(options
				(clearance outline)
				(anchor circle)
			)
			(primitives
				(gr_poly
					(pts
						(arc
							(start -0.1778 -0.2794)
							(mid -0.249642 -0.249642)
							(end -0.2794 -0.1778)
						)
						(arc
							(start -0.2794 0.1778)
							(mid -0.249642 0.249642)
							(end -0.1778 0.2794)
						)
						(arc
							(start 0.1778 0.2794)
							(mid 0.249642 0.249642)
							(end 0.2794 0.1778)
						)
						(arc
							(start 0.2794 -0.1778)
							(mid 0.249642 -0.249642)
							(end 0.1778 -0.2794)
						)
					)
					(width 0)
					(fill yes)
				)
			)
		)
	)
	(footprint ""
		(layer "F.Cu")
		(at 280.162 -161.544)
		(property "Reference" "R233"
			(at 0 0 0)
			(layer "F.SilkS")
			(hide yes)
			(effects
				(font
					(size 1.27 1.27)
				)
			)
		)
		(property "Value" "100KR2F-L1-GP"
			(at 0.064008 -3.993896 0)
			(unlocked yes)
			(layer "F.Fab")
			(hide yes)
			(effects
				(font
					(size 1.016 1.016)
					(thickness 0.1524)
				)
			)
		)
		(property "Device Type" "R402H16"
			(at 0.064008 -5.517896 0)
			(unlocked yes)
			(layer "F.Fab")
			(hide yes)
			(effects
				(font
					(size 1.016 1.016)
					(thickness 0.1524)
				)
			)
		)
		(duplicate_pad_numbers_are_jumpers no)
		(fp_line
			(start -0.508 -0.9398)
			(end -0.508 0.9398)
			(stroke
				(width 0.1524)
				(type default)
			)
			(layer "F.SilkS")
		)
		(fp_line
			(start 0.508 -0.9398)
			(end -0.508 -0.9398)
			(stroke
				(width 0.1524)
				(type default)
			)
			(layer "F.SilkS")
		)
		(fp_rect
			(start -0.508 0.9398)
			(end 0.508 -0.9398)
			(stroke
				(width 0)
				(type default)
			)
			(fill no)
			(layer "F.CrtYd")
		)
		(fp_rect
			(start -0.508 0.9398)
			(end 0.508 -0.9398)
			(stroke
				(width 0)
				(type default)
			)
			(fill no)
			(layer "F.Fab")
		)
		(pad "1" smd custom
			(at 0 -0.4445)
			(size 0.1397 0.1397)
			(layers "F.Cu" "F.Mask" "F.Paste")
			(net "TP_LPC_CPU_CLKOUT0")
			(options
				(clearance outline)
				(anchor circle)
			)
			(primitives
				(gr_poly
					(pts
						(arc
							(start -0.1778 -0.2794)
							(mid -0.249642 -0.249642)
							(end -0.2794 -0.1778)
						)
						(arc
							(start -0.2794 0.1778)
							(mid -0.249642 0.249642)
							(end -0.1778 0.2794)
						)
						(arc
							(start 0.1778 0.2794)
							(mid 0.249642 0.249642)
							(end 0.2794 0.1778)
						)
						(arc
							(start 0.2794 -0.1778)
							(mid 0.249642 -0.249642)
							(end 0.1778 -0.2794)
						)
					)
					(width 0)
					(fill yes)
				)
			)
		)
		(pad "2" smd custom
			(at 0 0.4445)
			(size 0.1397 0.1397)
			(layers "F.Cu" "F.Mask" "F.Paste")
			(net "GND")
			(options
				(clearance outline)
				(anchor circle)
			)
			(primitives
				(gr_poly
					(pts
						(arc
							(start -0.1778 -0.2794)
							(mid -0.249642 -0.249642)
							(end -0.2794 -0.1778)
						)
						(arc
							(start -0.2794 0.1778)
							(mid -0.249642 0.249642)
							(end -0.1778 0.2794)
						)
						(arc
							(start 0.1778 0.2794)
							(mid 0.249642 0.249642)
							(end 0.2794 0.1778)
						)
						(arc
							(start 0.2794 -0.1778)
							(mid 0.249642 -0.249642)
							(end 0.1778 -0.2794)
						)
					)
					(width 0)
					(fill yes)
				)
			)
		)
	)
)
